# BASEBOARD_FAB2 (Tioga Pass) — schematic netlist excerpt (pin names and nets, part order shuffled) for the footprints in the layout excerpt that follows; sources: Cadence DE-HDL packaged netlist, KiCad conversion of Wiwynn_Tioga_Pass_MB.brd

C8U9  CAP_A  47UF 4V 20% X5R  pkg 0603V  page 225 : A = PVDDQ_GHJ ; B = GND
C6W1  CAP_A  0.1UF 16V 10% X7R  pkg 0402V  page 247 : A = P3V3_STBY ; B = GND
C2T9  CAP  22UF 6.3V 20% X6S  pkg 0805  page 240 : A = P3V3_STBY ; B = GND

(kicad_pcb
	(version 20260206)
	(generator "pcbnew")
	(generator_version "10.0")
	(general
		(thickness 1.6)
		(legacy_teardrops no)
	)
	(paper "A4")
	(title_block
		(title "Wiwynn_Tioga_Pass_MB.brd")
		(comment 1 "Tioga Pass / footprints 2870-2872 of 4770")
	)
	(layers
		(0 "F.Cu" signal "TOP")
		(4 "In1.Cu" signal "L2GND")
		(6 "In2.Cu" signal "L3")
		(8 "In3.Cu" signal "L4GND")
		(10 "In4.Cu" signal "L5")
		(12 "In5.Cu" signal "L6GND")
		(14 "In6.Cu" signal "L7VCC")
		(16 "In7.Cu" signal "L8VCC")
		(18 "In8.Cu" signal "L9GND")
		(20 "In9.Cu" signal "L10")
		(22 "In10.Cu" signal "L11GND")
		(24 "In11.Cu" signal "L12")
		(26 "In12.Cu" signal "L13GND")
		(2 "B.Cu" signal "BOTTOM")
		(9 "F.Adhes" user "F.Adhesive")
		(11 "B.Adhes" user "B.Adhesive")
		(13 "F.Paste" user "Package Geometry/Pastemask Top")
		(15 "B.Paste" user "Package Geometry/Pastemask Bottom")
		(5 "F.SilkS" user "Ref Des/Silkscreen Top")
		(7 "B.SilkS" user "Ref Des/Silkscreen Bottom")
		(1 "F.Mask" user "Board Geometry/Soldermask Top")
		(3 "B.Mask" user "Board Geometry/Soldermask Bottom")
		(17 "Dwgs.User" user "User.Drawings")
		(19 "Cmts.User" user "User.Comments")
		(21 "Eco1.User" user "User.Eco1")
		(23 "Eco2.User" user "User.Eco2")
		(25 "Edge.Cuts" user "Board Geometry/Outline")
		(27 "Margin" user)
		(31 "F.CrtYd" user "Package Geometry/Place Bound Top")
		(29 "B.CrtYd" user "Package Geometry/Place Bound Bottom")
		(35 "F.Fab" user "Ref Des/Assembly Top")
		(33 "B.Fab" user "Ref Des/Assembly Bottom")
	)
	(footprint ""
		(layer "B.Cu")
		(at 93.444568 -8.0772 -90)
		(property "Reference" "C8U9"
			(at 0 0 90)
			(layer "B.SilkS")
			(hide yes)
			(effects
				(font
					(size 1.27 1.27)
				)
				(justify mirror)
			)
		)
		(property "Value" ""
			(at 0 0 90)
			(layer "B.Fab")
			(effects
				(font
					(size 1.27 1.27)
				)
				(justify mirror)
			)
		)
		(duplicate_pad_numbers_are_jumpers no)
		(fp_rect
			(start 0.500126 1.598422)
			(end -0.500126 -0.201422)
			(stroke
				(width 0)
				(type default)
			)
			(fill no)
			(layer "B.CrtYd")
		)
		(fp_line
			(start -0.500126 1.598422)
			(end 0.500126 1.598422)
			(stroke
				(width 0.1)
				(type default)
			)
			(layer "B.Fab")
		)
		(fp_line
			(start 0.500126 1.598422)
			(end 0.500126 -0.201422)
			(stroke
				(width 0.1)
				(type default)
			)
			(layer "B.Fab")
		)
		(fp_line
			(start -0.500126 -0.201422)
			(end -0.500126 1.598422)
			(stroke
				(width 0.1)
				(type default)
			)
			(layer "B.Fab")
		)
		(fp_line
			(start 0.500126 -0.201422)
			(end -0.500126 -0.201422)
			(stroke
				(width 0.1)
				(type default)
			)
			(layer "B.Fab")
		)
		(pad "1" smd rect
			(at 0 0 180)
			(size 0.889 0.9906)
			(layers "B.Cu" "B.Mask" "B.Paste")
			(net "PVDDQ_GHJ")
		)
		(pad "2" smd rect
			(at 0 1.397 180)
			(size 0.889 0.9906)
			(layers "B.Cu" "B.Mask" "B.Paste")
			(net "GND")
		)
		(zone
			(layer "B.Cu")
			(hatch none 0.5)
			(connect_pads
				(clearance 0)
			)
			(min_thickness 0.25)
			(keepout
				(tracks allowed)
				(vias not_allowed)
				(pads allowed)
				(copperpour not_allowed)
				(footprints allowed)
			)
			(placement
				(enabled no)
				(sheetname "")
			)
			(fill
				(thermal_gap 0.5)
				(thermal_bridge_width 0.5)
				(island_removal_mode 0)
			)
			(polygon
				(pts
					(xy 92.492068 -7.5819) (xy 93.000068 -7.5819) (xy 93.000068 -8.5725) (xy 92.492068 -8.5725)
				)
			)
		)
		(zone
			(layer "B.Cu")
			(hatch none 0.5)
			(connect_pads
				(clearance 0)
			)
			(min_thickness 0.25)
			(keepout
				(tracks not_allowed)
				(vias allowed)
				(pads allowed)
				(copperpour not_allowed)
				(footprints allowed)
			)
			(placement
				(enabled no)
				(sheetname "")
			)
			(fill
				(thermal_gap 0.5)
				(thermal_bridge_width 0.5)
				(island_removal_mode 0)
			)
			(polygon
				(pts
					(xy 92.492068 -7.5819) (xy 93.000068 -7.5819) (xy 93.000068 -8.5725) (xy 92.492068 -8.5725)
				)
			)
		)
	)
	(footprint ""
		(layer "B.Cu")
		(at 458.08773 -18.55724)
		(property "Reference" "C2T9"
			(at 0 0 0)
			(layer "B.SilkS")
			(hide yes)
			(effects
				(font
					(size 1.27 1.27)
				)
				(justify mirror)
			)
		)
		(property "Value" ""
			(at 0 0 0)
			(layer "B.Fab")
			(effects
				(font
					(size 1.27 1.27)
				)
				(justify mirror)
			)
		)
		(duplicate_pad_numbers_are_jumpers no)
		(fp_poly
			(pts
				(xy 0.7239 -0.2159) (xy -0.7239 -0.2159) (xy -0.7239 1.9939) (xy 0.7239 1.9939)
			)
			(stroke
				(width 0)
				(type default)
			)
			(fill no)
			(layer "B.CrtYd")
		)
		(fp_line
			(start -0.7239 -0.2159)
			(end 0.7239 -0.2159)
			(stroke
				(width 0.1)
				(type default)
			)
			(layer "B.Fab")
		)
		(fp_line
			(start -0.7239 1.9939)
			(end -0.7239 -0.2159)
			(stroke
				(width 0.1)
				(type default)
			)
			(layer "B.Fab")
		)
		(fp_line
			(start 0.7239 -0.2159)
			(end 0.7239 1.9939)
			(stroke
				(width 0.1)
				(type default)
			)
			(layer "B.Fab")
		)
		(fp_line
			(start 0.7239 1.9939)
			(end -0.7239 1.9939)
			(stroke
				(width 0.1)
				(type default)
			)
			(layer "B.Fab")
		)
		(pad "1" smd rect
			(at 0 0 180)
			(size 1.27 1.016)
			(layers "B.Cu" "B.Mask" "B.Paste")
			(net "P3V3_STBY")
		)
		(pad "2" smd rect
			(at 0 1.778 180)
			(size 1.27 1.016)
			(layers "B.Cu" "B.Mask" "B.Paste")
			(net "GND")
		)
		(zone
			(layer "B.Cu")
			(hatch none 0.5)
			(connect_pads
				(clearance 0)
			)
			(min_thickness 0.25)
			(keepout
				(tracks not_allowed)
				(vias allowed)
				(pads allowed)
				(copperpour not_allowed)
				(footprints allowed)
			)
			(placement
				(enabled no)
				(sheetname "")
			)
			(fill
				(thermal_gap 0.5)
				(thermal_bridge_width 0.5)
				(island_removal_mode 0)
			)
			(polygon
				(pts
					(xy 458.72273 -18.04924) (xy 457.45273 -18.04924) (xy 457.45273 -17.28724) (xy 458.72273 -17.28724)
				)
			)
		)
	)
	(footprint ""
		(layer "B.Cu")
		(at 473.719652 -145.477484 -90)
		(property "Reference" "C6W1"
			(at 0.8382 -0.67818 270)
			(unlocked yes)
			(layer "B.SilkS")
			(effects
				(font
					(size 0.4064 0.254)
					(thickness 0.1524)
				)
				(justify left mirror)
			)
		)
		(property "Value" ""
			(at 0 0 90)
			(layer "B.Fab")
			(effects
				(font
					(size 1.27 1.27)
				)
				(justify mirror)
			)
		)
		(duplicate_pad_numbers_are_jumpers no)
		(fp_poly
			(pts
				(xy -0.3048 -0.1016) (xy -0.3048 0.9906) (xy 0.3048 0.9906) (xy 0.3048 -0.1016)
			)
			(stroke
				(width 0)
				(type default)
			)
			(fill no)
			(layer "B.CrtYd")
		)
		(fp_line
			(start -0.3048 0.9906)
			(end -0.3048 -0.1016)
			(stroke
				(width 0.1)
				(type default)
			)
			(layer "B.Fab")
		)
		(fp_line
			(start 0.3048 0.9906)
			(end -0.3048 0.9906)
			(stroke
				(width 0.1)
				(type default)
			)
			(layer "B.Fab")
		)
		(fp_line
			(start -0.3048 -0.1016)
			(end 0.3048 -0.1016)
			(stroke
				(width 0.1)
				(type default)
			)
			(layer "B.Fab")
		)
		(fp_line
			(start 0.3048 -0.1016)
			(end 0.3048 0.9906)
			(stroke
				(width 0.1)
				(type default)
			)
			(layer "B.Fab")
		)
		(pad "1" smd rect
			(at 0 0 90)
			(size 0.508 0.508)
			(layers "B.Cu" "B.Mask" "B.Paste")
			(net "P3V3_STBY")
		)
		(pad "2" smd rect
			(at 0 0.889 90)
			(size 0.508 0.508)
			(layers "B.Cu" "B.Mask" "B.Paste")
			(net "GND")
		)
		(zone
			(layer "B.Cu")
			(hatch none 0.5)
			(connect_pads
				(clearance 0)
			)
			(min_thickness 0.25)
			(keepout
				(tracks not_allowed)
				(vias allowed)
				(pads allowed)
				(copperpour not_allowed)
				(footprints allowed)
			)
			(placement
				(enabled no)
				(sheetname "")
			)
			(fill
				(thermal_gap 0.5)
				(thermal_bridge_width 0.5)
				(island_removal_mode 0)
			)
			(polygon
				(pts
					(xy 473.084652 -145.223484) (xy 473.084652 -145.731484) (xy 473.465652 -145.731484) (xy 473.465652 -145.223484)
				)
			)
		)
		(zone
			(layer "B.Cu")
			(hatch none 0.5)
			(connect_pads
				(clearance 0)
			)
			(min_thickness 0.25)
			(keepout
				(tracks allowed)
				(vias not_allowed)
				(pads allowed)
				(copperpour not_allowed)
				(footprints allowed)
			)
			(placement
				(enabled no)
				(sheetname "")
			)
			(fill
				(thermal_gap 0.5)
				(thermal_bridge_width 0.5)
				(island_removal_mode 0)
			)
			(polygon
				(pts
					(xy 473.465652 -145.223484) (xy 473.465652 -145.731484) (xy 473.084652 -145.731484) (xy 473.084652 -145.223484)
				)
			)
		)
	)
)
